# BASEBOARD_FAB2 (Tioga Pass) — schematic netlist excerpt (pin names and nets, part order shuffled) for the footprints in the layout excerpt that follows; sources: Cadence DE-HDL packaged netlist, KiCad conversion of Wiwynn_Tioga_Pass_MB.brd

CT30  CAP_A  0.1UF 16V 10% X7R  pkg 0402V  page 224 : A = VR_PVDDQ_GHJ_AIREF1 ; B = GND
R3N10  RES  10.0K 1% CHIP  pkg 0402  page 121 : A = P3V3_STBY ; B = FM_INTRUDER_HDR_PCH_N
R4T10  RES  20.0 1% CHIP  pkg 0402  page 99 : A = SMB_DDR_ABC_VPP_SDA_R ; B = SMB_DDR_ABC_VPP_SDA

(kicad_pcb
	(version 20260206)
	(generator "pcbnew")
	(generator_version "10.0")
	(general
		(thickness 1.6)
		(legacy_teardrops no)
	)
	(paper "A4")
	(title_block
		(title "Wiwynn_Tioga_Pass_MB.brd")
		(comment 1 "Tioga Pass / footprints 3597-3599 of 4770")
	)
	(layers
		(0 "F.Cu" signal "TOP")
		(4 "In1.Cu" signal "L2GND")
		(6 "In2.Cu" signal "L3")
		(8 "In3.Cu" signal "L4GND")
		(10 "In4.Cu" signal "L5")
		(12 "In5.Cu" signal "L6GND")
		(14 "In6.Cu" signal "L7VCC")
		(16 "In7.Cu" signal "L8VCC")
		(18 "In8.Cu" signal "L9GND")
		(20 "In9.Cu" signal "L10")
		(22 "In10.Cu" signal "L11GND")
		(24 "In11.Cu" signal "L12")
		(26 "In12.Cu" signal "L13GND")
		(2 "B.Cu" signal "BOTTOM")
		(9 "F.Adhes" user "F.Adhesive")
		(11 "B.Adhes" user "B.Adhesive")
		(13 "F.Paste" user "Package Geometry/Pastemask Top")
		(15 "B.Paste" user "Package Geometry/Pastemask Bottom")
		(5 "F.SilkS" user "Ref Des/Silkscreen Top")
		(7 "B.SilkS" user "Ref Des/Silkscreen Bottom")
		(1 "F.Mask" user "Board Geometry/Soldermask Top")
		(3 "B.Mask" user "Board Geometry/Soldermask Bottom")
		(17 "Dwgs.User" user "User.Drawings")
		(19 "Cmts.User" user "User.Comments")
		(21 "Eco1.User" user "User.Eco1")
		(23 "Eco2.User" user "User.Eco2")
		(25 "Edge.Cuts" user "Board Geometry/Outline")
		(27 "Margin" user)
		(31 "F.CrtYd" user "Package Geometry/Place Bound Top")
		(29 "B.CrtYd" user "Package Geometry/Place Bound Bottom")
		(35 "F.Fab" user "Ref Des/Assembly Top")
		(33 "B.Fab" user "Ref Des/Assembly Bottom")
	)
	(footprint ""
		(layer "B.Cu")
		(at 386.08 -87.3125 180)
		(property "Reference" "R3N10"
			(at 0 0 0)
			(layer "B.SilkS")
			(hide yes)
			(effects
				(font
					(size 1.27 1.27)
				)
				(justify mirror)
			)
		)
		(property "Value" ""
			(at 0 0 0)
			(layer "B.Fab")
			(effects
				(font
					(size 1.27 1.27)
				)
				(justify mirror)
			)
		)
		(duplicate_pad_numbers_are_jumpers no)
		(fp_poly
			(pts
				(xy 0.2794 -0.1016) (xy -0.2794 -0.1016) (xy -0.2794 0.9906) (xy 0.2794 0.9906)
			)
			(stroke
				(width 0)
				(type default)
			)
			(fill no)
			(layer "B.CrtYd")
		)
		(fp_line
			(start 0.2794 0.9906)
			(end -0.2794 0.9906)
			(stroke
				(width 0.1)
				(type default)
			)
			(layer "B.Fab")
		)
		(fp_line
			(start 0.2794 -0.1016)
			(end 0.2794 0.9906)
			(stroke
				(width 0.1)
				(type default)
			)
			(layer "B.Fab")
		)
		(fp_line
			(start -0.2794 0.9906)
			(end -0.2794 -0.1016)
			(stroke
				(width 0.1)
				(type default)
			)
			(layer "B.Fab")
		)
		(fp_line
			(start -0.2794 -0.1016)
			(end 0.2794 -0.1016)
			(stroke
				(width 0.1)
				(type default)
			)
			(layer "B.Fab")
		)
		(pad "1" smd rect
			(at 0 0)
			(size 0.508 0.508)
			(layers "B.Cu" "B.Mask" "B.Paste")
			(net "P3V3_STBY")
		)
		(pad "2" smd rect
			(at 0 0.889)
			(size 0.508 0.508)
			(layers "B.Cu" "B.Mask" "B.Paste")
			(net "FM_INTRUDER_HDR_PCH_N")
		)
		(zone
			(layer "B.Cu")
			(hatch none 0.5)
			(connect_pads
				(clearance 0)
			)
			(min_thickness 0.25)
			(keepout
				(tracks not_allowed)
				(vias allowed)
				(pads allowed)
				(copperpour not_allowed)
				(footprints allowed)
			)
			(placement
				(enabled no)
				(sheetname "")
			)
			(fill
				(thermal_gap 0.5)
				(thermal_bridge_width 0.5)
				(island_removal_mode 0)
			)
			(polygon
				(pts
					(xy 385.826 -87.9475) (xy 386.334 -87.9475) (xy 386.334 -87.5665) (xy 385.826 -87.5665)
				)
			)
		)
		(zone
			(layer "B.Cu")
			(hatch none 0.5)
			(connect_pads
				(clearance 0)
			)
			(min_thickness 0.25)
			(keepout
				(tracks allowed)
				(vias not_allowed)
				(pads allowed)
				(copperpour not_allowed)
				(footprints allowed)
			)
			(placement
				(enabled no)
				(sheetname "")
			)
			(fill
				(thermal_gap 0.5)
				(thermal_bridge_width 0.5)
				(island_removal_mode 0)
			)
			(polygon
				(pts
					(xy 385.826 -87.5665) (xy 386.334 -87.5665) (xy 386.334 -87.9475) (xy 385.826 -87.9475)
				)
			)
		)
	)
	(footprint ""
		(layer "B.Cu")
		(at 322.0847 -27.34818 -90)
		(property "Reference" "R4T10"
			(at 0 0 90)
			(layer "B.SilkS")
			(hide yes)
			(effects
				(font
					(size 1.27 1.27)
				)
				(justify mirror)
			)
		)
		(property "Value" ""
			(at 0 0 90)
			(layer "B.Fab")
			(effects
				(font
					(size 1.27 1.27)
				)
				(justify mirror)
			)
		)
		(duplicate_pad_numbers_are_jumpers no)
		(fp_poly
			(pts
				(xy 0.2794 -0.1016) (xy -0.2794 -0.1016) (xy -0.2794 0.9906) (xy 0.2794 0.9906)
			)
			(stroke
				(width 0)
				(type default)
			)
			(fill no)
			(layer "B.CrtYd")
		)
		(fp_line
			(start -0.2794 0.9906)
			(end -0.2794 -0.1016)
			(stroke
				(width 0.1)
				(type default)
			)
			(layer "B.Fab")
		)
		(fp_line
			(start 0.2794 0.9906)
			(end -0.2794 0.9906)
			(stroke
				(width 0.1)
				(type default)
			)
			(layer "B.Fab")
		)
		(fp_line
			(start -0.2794 -0.1016)
			(end 0.2794 -0.1016)
			(stroke
				(width 0.1)
				(type default)
			)
			(layer "B.Fab")
		)
		(fp_line
			(start 0.2794 -0.1016)
			(end 0.2794 0.9906)
			(stroke
				(width 0.1)
				(type default)
			)
			(layer "B.Fab")
		)
		(pad "1" smd rect
			(at 0 0 90)
			(size 0.508 0.508)
			(layers "B.Cu" "B.Mask" "B.Paste")
			(net "SMB_DDR_ABC_VPP_SDA_R")
		)
		(pad "2" smd rect
			(at 0 0.889 90)
			(size 0.508 0.508)
			(layers "B.Cu" "B.Mask" "B.Paste")
			(net "SMB_DDR_ABC_VPP_SDA")
		)
		(zone
			(layer "B.Cu")
			(hatch none 0.5)
			(connect_pads
				(clearance 0)
			)
			(min_thickness 0.25)
			(keepout
				(tracks not_allowed)
				(vias allowed)
				(pads allowed)
				(copperpour not_allowed)
				(footprints allowed)
			)
			(placement
				(enabled no)
				(sheetname "")
			)
			(fill
				(thermal_gap 0.5)
				(thermal_bridge_width 0.5)
				(island_removal_mode 0)
			)
			(polygon
				(pts
					(xy 321.4497 -27.09418) (xy 321.4497 -27.60218) (xy 321.8307 -27.60218) (xy 321.8307 -27.09418)
				)
			)
		)
		(zone
			(layer "B.Cu")
			(hatch none 0.5)
			(connect_pads
				(clearance 0)
			)
			(min_thickness 0.25)
			(keepout
				(tracks allowed)
				(vias not_allowed)
				(pads allowed)
				(copperpour not_allowed)
				(footprints allowed)
			)
			(placement
				(enabled no)
				(sheetname "")
			)
			(fill
				(thermal_gap 0.5)
				(thermal_bridge_width 0.5)
				(island_removal_mode 0)
			)
			(polygon
				(pts
					(xy 321.8307 -27.09418) (xy 321.8307 -27.60218) (xy 321.4497 -27.60218) (xy 321.4497 -27.09418)
				)
			)
		)
	)
	(footprint ""
		(layer "B.Cu")
		(at 1.38176 -5.35686 90)
		(property "Reference" "CT30"
			(at 0.43307 14.8844 180)
			(unlocked yes)
			(layer "B.SilkS")
			(effects
				(font
					(size 0.7874 0.5842)
					(thickness 0.1524)
				)
				(justify left mirror)
			)
		)
		(property "Value" ""
			(at 0 0 90)
			(layer "B.Fab")
			(effects
				(font
					(size 1.27 1.27)
				)
				(justify mirror)
			)
		)
		(duplicate_pad_numbers_are_jumpers no)
		(fp_rect
			(start -0.3048 -0.1016)
			(end 0.3048 0.9906)
			(stroke
				(width 0)
				(type default)
			)
			(fill no)
			(layer "B.CrtYd")
		)
		(fp_line
			(start 0.3048 -0.1016)
			(end 0.3048 0.9906)
			(stroke
				(width 0.1)
				(type default)
			)
			(layer "B.Fab")
		)
		(fp_line
			(start -0.3048 -0.1016)
			(end 0.3048 -0.1016)
			(stroke
				(width 0.1)
				(type default)
			)
			(layer "B.Fab")
		)
		(fp_line
			(start 0.3048 0.9906)
			(end -0.3048 0.9906)
			(stroke
				(width 0.1)
				(type default)
			)
			(layer "B.Fab")
		)
		(fp_line
			(start -0.3048 0.9906)
			(end -0.3048 -0.1016)
			(stroke
				(width 0.1)
				(type default)
			)
			(layer "B.Fab")
		)
		(pad "1" smd rect
			(at 0 0 270)
			(size 0.508 0.508)
			(layers "B.Cu" "B.Mask" "B.Paste")
			(net "VR_PVDDQ_GHJ_AIREF1")
		)
		(pad "2" smd rect
			(at 0 0.889 270)
			(size 0.508 0.508)
			(layers "B.Cu" "B.Mask" "B.Paste")
			(net "GND")
		)
		(zone
			(layer "B.Cu")
			(hatch none 0.5)
			(connect_pads
				(clearance 0)
			)
			(min_thickness 0.25)
			(keepout
				(tracks allowed)
				(vias not_allowed)
				(pads allowed)
				(copperpour not_allowed)
				(footprints allowed)
			)
			(placement
				(enabled no)
				(sheetname "")
			)
			(fill
				(thermal_gap 0.5)
				(thermal_bridge_width 0.5)
				(island_removal_mode 0)
			)
			(polygon
				(pts
					(xy 1.63576 -5.10286) (xy 2.01676 -5.10286) (xy 2.01676 -5.61086) (xy 1.63576 -5.61086)
				)
			)
		)
		(zone
			(layer "B.Cu")
			(hatch none 0.5)
			(connect_pads
				(clearance 0)
			)
			(min_thickness 0.25)
			(keepout
				(tracks not_allowed)
				(vias allowed)
				(pads allowed)
				(copperpour not_allowed)
				(footprints allowed)
			)
			(placement
				(enabled no)
				(sheetname "")
			)
			(fill
				(thermal_gap 0.5)
				(thermal_bridge_width 0.5)
				(island_removal_mode 0)
			)
			(polygon
				(pts
					(xy 1.63576 -5.10286) (xy 2.01676 -5.10286) (xy 2.01676 -5.61086) (xy 1.63576 -5.61086)
				)
			)
		)
	)
)
